# BASEBOARD_FAB2 (Tioga Pass) — schematic netlist excerpt (pin names and nets, part order shuffled) for the footprints in the layout excerpt that follows; sources: Cadence DE-HDL packaged netlist, KiCad conversion of Wiwynn_Tioga_Pass_MB.brd

R30W2  RES  0.0 5% CHIP  pkg 0402  page 253 : A = USB3_P01_RXP ; B = USB3_P01_FB_RXP
C8M7  CAP  100UF 4V 20% X5R  pkg 0805  page 228 : A = PVDDQ_KLM ; B = GND

U1M4  74CBTLV1G125  IC  pkg SMLF  page 112
  OE_N  = FM_CPU1_SKTOCC_LVT3_N
  A  = XDP_CPU0_TDO
  B  = XDP_CPU1_TDI

(kicad_pcb
	(version 20260206)
	(generator "pcbnew")
	(generator_version "10.0")
	(general
		(thickness 1.6)
		(legacy_teardrops no)
	)
	(paper "A4")
	(title_block
		(title "Wiwynn_Tioga_Pass_MB.brd")
		(comment 1 "Tioga Pass / footprints 4011-4013 of 4770")
	)
	(layers
		(0 "F.Cu" signal "TOP")
		(4 "In1.Cu" signal "L2GND")
		(6 "In2.Cu" signal "L3")
		(8 "In3.Cu" signal "L4GND")
		(10 "In4.Cu" signal "L5")
		(12 "In5.Cu" signal "L6GND")
		(14 "In6.Cu" signal "L7VCC")
		(16 "In7.Cu" signal "L8VCC")
		(18 "In8.Cu" signal "L9GND")
		(20 "In9.Cu" signal "L10")
		(22 "In10.Cu" signal "L11GND")
		(24 "In11.Cu" signal "L12")
		(26 "In12.Cu" signal "L13GND")
		(2 "B.Cu" signal "BOTTOM")
		(9 "F.Adhes" user "F.Adhesive")
		(11 "B.Adhes" user "B.Adhesive")
		(13 "F.Paste" user "Package Geometry/Pastemask Top")
		(15 "B.Paste" user "Package Geometry/Pastemask Bottom")
		(5 "F.SilkS" user "Ref Des/Silkscreen Top")
		(7 "B.SilkS" user "Ref Des/Silkscreen Bottom")
		(1 "F.Mask" user "Board Geometry/Soldermask Top")
		(3 "B.Mask" user "Board Geometry/Soldermask Bottom")
		(17 "Dwgs.User" user "User.Drawings")
		(19 "Cmts.User" user "User.Comments")
		(21 "Eco1.User" user "User.Eco1")
		(23 "Eco2.User" user "User.Eco2")
		(25 "Edge.Cuts" user "Board Geometry/Outline")
		(27 "Margin" user)
		(31 "F.CrtYd" user "Package Geometry/Place Bound Top")
		(29 "B.CrtYd" user "Package Geometry/Place Bound Bottom")
		(35 "F.Fab" user "Ref Des/Assembly Top")
		(33 "B.Fab" user "Ref Des/Assembly Bottom")
	)
	(footprint ""
		(layer "B.Cu")
		(at 460.4512 -129.6924 90)
		(property "Reference" "U1M4"
			(at -0.34036 2.28473 270)
			(unlocked yes)
			(layer "B.SilkS")
			(effects
				(font
					(size 0.7874 0.5842)
					(thickness 0.1524)
				)
				(justify left mirror)
			)
		)
		(property "Value" ""
			(at 0 0 90)
			(layer "B.Fab")
			(effects
				(font
					(size 1.27 1.27)
				)
				(justify mirror)
			)
		)
		(duplicate_pad_numbers_are_jumpers no)
		(fp_circle
			(center 0.858012 -0.008636)
			(end 0.858012 0.118364)
			(stroke
				(width 0.254)
				(type default)
			)
			(fill no)
			(layer "B.SilkS")
		)
		(fp_poly
			(pts
				(xy -0.21463 -0.450088) (xy -1.56337 -0.450088) (xy -1.56337 1.75006) (xy -0.21463 1.75006)
			)
			(stroke
				(width 0)
				(type default)
			)
			(fill no)
			(layer "B.CrtYd")
		)
		(fp_line
			(start -0.21463 -0.450088)
			(end -1.56337 -0.450088)
			(stroke
				(width 0.1)
				(type default)
			)
			(layer "B.Fab")
		)
		(fp_line
			(start -1.56337 -0.450088)
			(end -1.56337 1.75006)
			(stroke
				(width 0.1)
				(type default)
			)
			(layer "B.Fab")
		)
		(fp_line
			(start -0.21463 1.75006)
			(end -0.21463 -0.450088)
			(stroke
				(width 0.1)
				(type default)
			)
			(layer "B.Fab")
		)
		(fp_line
			(start -1.56337 1.75006)
			(end -0.21463 1.75006)
			(stroke
				(width 0.1)
				(type default)
			)
			(layer "B.Fab")
		)
		(fp_circle
			(center 0.4699 -0.8382)
			(end 0.4699 -0.7112)
			(stroke
				(width 0.254)
				(type default)
			)
			(fill no)
			(layer "B.Fab")
		)
		(pad "1" smd rect
			(at 0 0 270)
			(size 1.016 0.381)
			(layers "B.Cu" "B.Mask" "B.Paste")
			(net "FM_CPU1_SKTOCC_LVT3_N")
		)
		(pad "2" smd rect
			(at 0 0.649986 270)
			(size 1.016 0.381)
			(layers "B.Cu" "B.Mask" "B.Paste")
			(net "XDP_CPU0_TDO")
		)
		(pad "3" smd rect
			(at 0 1.299972 270)
			(size 1.016 0.381)
			(layers "B.Cu" "B.Mask" "B.Paste")
			(net "GND")
		)
		(pad "4" smd rect
			(at -1.778 1.299972 270)
			(size 1.016 0.381)
			(layers "B.Cu" "B.Mask" "B.Paste")
			(net "XDP_CPU1_TDI")
		)
		(pad "5" smd rect
			(at -1.778 0 270)
			(size 1.016 0.381)
			(layers "B.Cu" "B.Mask" "B.Paste")
			(net "P3V3_STBY")
		)
	)
	(footprint ""
		(layer "B.Cu")
		(at 486.119424 -58.104024 90)
		(property "Reference" "R30W2"
			(at 0.8382 -0.67818 90)
			(unlocked yes)
			(layer "B.SilkS")
			(effects
				(font
					(size 0.4064 0.254)
					(thickness 0.1524)
				)
				(justify left mirror)
			)
		)
		(property "Value" ""
			(at 0 0 90)
			(layer "B.Fab")
			(effects
				(font
					(size 1.27 1.27)
				)
				(justify mirror)
			)
		)
		(duplicate_pad_numbers_are_jumpers no)
		(fp_poly
			(pts
				(xy 0.2794 -0.1016) (xy -0.2794 -0.1016) (xy -0.2794 0.9906) (xy 0.2794 0.9906)
			)
			(stroke
				(width 0)
				(type default)
			)
			(fill no)
			(layer "B.CrtYd")
		)
		(fp_line
			(start 0.2794 -0.1016)
			(end 0.2794 0.9906)
			(stroke
				(width 0.1)
				(type default)
			)
			(layer "B.Fab")
		)
		(fp_line
			(start -0.2794 -0.1016)
			(end 0.2794 -0.1016)
			(stroke
				(width 0.1)
				(type default)
			)
			(layer "B.Fab")
		)
		(fp_line
			(start 0.2794 0.9906)
			(end -0.2794 0.9906)
			(stroke
				(width 0.1)
				(type default)
			)
			(layer "B.Fab")
		)
		(fp_line
			(start -0.2794 0.9906)
			(end -0.2794 -0.1016)
			(stroke
				(width 0.1)
				(type default)
			)
			(layer "B.Fab")
		)
		(pad "1" smd rect
			(at 0 0 270)
			(size 0.508 0.508)
			(layers "B.Cu" "B.Mask" "B.Paste")
			(net "USB3_P01_RXP")
		)
		(pad "2" smd rect
			(at 0 0.889 270)
			(size 0.508 0.508)
			(layers "B.Cu" "B.Mask" "B.Paste")
			(net "USB3_P01_FB_RXP")
		)
		(zone
			(layer "B.Cu")
			(hatch none 0.5)
			(connect_pads
				(clearance 0)
			)
			(min_thickness 0.25)
			(keepout
				(tracks allowed)
				(vias not_allowed)
				(pads allowed)
				(copperpour not_allowed)
				(footprints allowed)
			)
			(placement
				(enabled no)
				(sheetname "")
			)
			(fill
				(thermal_gap 0.5)
				(thermal_bridge_width 0.5)
				(island_removal_mode 0)
			)
			(polygon
				(pts
					(xy 486.373424 -58.358024) (xy 486.373424 -57.850024) (xy 486.754424 -57.850024) (xy 486.754424 -58.358024)
				)
			)
		)
		(zone
			(layer "B.Cu")
			(hatch none 0.5)
			(connect_pads
				(clearance 0)
			)
			(min_thickness 0.25)
			(keepout
				(tracks not_allowed)
				(vias allowed)
				(pads allowed)
				(copperpour not_allowed)
				(footprints allowed)
			)
			(placement
				(enabled no)
				(sheetname "")
			)
			(fill
				(thermal_gap 0.5)
				(thermal_bridge_width 0.5)
				(island_removal_mode 0)
			)
			(polygon
				(pts
					(xy 486.754424 -58.358024) (xy 486.754424 -57.850024) (xy 486.373424 -57.850024) (xy 486.373424 -58.358024)
				)
			)
		)
	)
	(footprint ""
		(layer "B.Cu")
		(at 94.300548 -135.376412 90)
		(property "Reference" "C8M7"
			(at 0 0 90)
			(layer "B.SilkS")
			(hide yes)
			(effects
				(font
					(size 1.27 1.27)
				)
				(justify mirror)
			)
		)
		(property "Value" ""
			(at 0 0 90)
			(layer "B.Fab")
			(effects
				(font
					(size 1.27 1.27)
				)
				(justify mirror)
			)
		)
		(duplicate_pad_numbers_are_jumpers no)
		(fp_poly
			(pts
				(xy 0.7239 -0.2159) (xy -0.7239 -0.2159) (xy -0.7239 1.9939) (xy 0.7239 1.9939)
			)
			(stroke
				(width 0)
				(type default)
			)
			(fill no)
			(layer "B.CrtYd")
		)
		(fp_line
			(start 0.7239 -0.2159)
			(end 0.7239 1.9939)
			(stroke
				(width 0.1)
				(type default)
			)
			(layer "B.Fab")
		)
		(fp_line
			(start -0.7239 -0.2159)
			(end 0.7239 -0.2159)
			(stroke
				(width 0.1)
				(type default)
			)
			(layer "B.Fab")
		)
		(fp_line
			(start 0.7239 1.9939)
			(end -0.7239 1.9939)
			(stroke
				(width 0.1)
				(type default)
			)
			(layer "B.Fab")
		)
		(fp_line
			(start -0.7239 1.9939)
			(end -0.7239 -0.2159)
			(stroke
				(width 0.1)
				(type default)
			)
			(layer "B.Fab")
		)
		(pad "1" smd rect
			(at 0 0 270)
			(size 1.27 1.016)
			(layers "B.Cu" "B.Mask" "B.Paste")
			(net "PVDDQ_KLM")
		)
		(pad "2" smd rect
			(at 0 1.778 270)
			(size 1.27 1.016)
			(layers "B.Cu" "B.Mask" "B.Paste")
			(net "GND")
		)
		(zone
			(layer "B.Cu")
			(hatch none 0.5)
			(connect_pads
				(clearance 0)
			)
			(min_thickness 0.25)
			(keepout
				(tracks not_allowed)
				(vias allowed)
				(pads allowed)
				(copperpour not_allowed)
				(footprints allowed)
			)
			(placement
				(enabled no)
				(sheetname "")
			)
			(fill
				(thermal_gap 0.5)
				(thermal_bridge_width 0.5)
				(island_removal_mode 0)
			)
			(polygon
				(pts
					(xy 94.808548 -136.011412) (xy 94.808548 -134.741412) (xy 95.570548 -134.741412) (xy 95.570548 -136.011412)
				)
			)
		)
	)
)
